# S9S_MB_2U (Grand Teton) — schematic netlist excerpt (pin names and nets, part order shuffled) for the footprints in the layout excerpt that follows; sources: Cadence DE-HDL packaged netlist, KiCad conversion of 03242023_DA0F0TMBIJ0_F0T_Motherboard_J_brd_V01_OCP.brd

PC482_P1_7  Q_CAP  2.2UF 10V 10% X6S  pkg C0402  page 288 : A = PVCCIN_CPU1_PVCC ; B = GND
C2264  Q_CAP  1000PF 50V 5% EMPTY  pkg 0402  page 146 : A = GPU_3V3IO_RSVD0_FFU_ISO ; B = GND

(kicad_pcb
	(version 20260206)
	(generator "pcbnew")
	(generator_version "10.0")
	(general
		(thickness 1.6)
		(legacy_teardrops no)
	)
	(paper "A4")
	(title_block
		(title "03242023_DA0F0TMBIJ0_F0T_Motherboard_J_brd_V01_OCP.brd")
		(comment 1 "Grand Teton / footprints 77-78 of 6105")
	)
	(layers
		(0 "F.Cu" signal "TOP")
		(4 "In1.Cu" signal "GND")
		(6 "In2.Cu" signal "IN1")
		(8 "In3.Cu" signal "GND1")
		(10 "In4.Cu" signal "IN2")
		(12 "In5.Cu" signal "GND2")
		(14 "In6.Cu" signal "IN3")
		(16 "In7.Cu" signal "GND3")
		(18 "In8.Cu" signal "VCC")
		(20 "In9.Cu" signal "VCC1")
		(22 "In10.Cu" signal "GND4")
		(24 "In11.Cu" signal "IN4")
		(26 "In12.Cu" signal "GND5")
		(28 "In13.Cu" signal "IN5")
		(30 "In14.Cu" signal "GND6")
		(32 "In15.Cu" signal "IN6")
		(34 "In16.Cu" signal "GND7")
		(2 "B.Cu" signal "BOTTOM")
		(9 "F.Adhes" user "F.Adhesive")
		(11 "B.Adhes" user "B.Adhesive")
		(13 "F.Paste" user "Package Geometry/Pastemask Top")
		(15 "B.Paste" user "Package Geometry/Pastemask Bottom")
		(5 "F.SilkS" user "Ref Des/Silkscreen Top")
		(7 "B.SilkS" user "Ref Des/Silkscreen Bottom")
		(1 "F.Mask" user "Board Geometry/Soldermask Top")
		(3 "B.Mask" user "Board Geometry/Soldermask Bottom")
		(17 "Dwgs.User" user "User.Drawings")
		(19 "Cmts.User" user "User.Comments")
		(21 "Eco1.User" user "User.Eco1")
		(23 "Eco2.User" user "User.Eco2")
		(25 "Edge.Cuts" user "Board Geometry/Outline")
		(27 "Margin" user)
		(31 "F.CrtYd" user "Package Geometry/Place Bound Top")
		(29 "B.CrtYd" user "Package Geometry/Place Bound Bottom")
		(35 "F.Fab" user "Ref Des/Assembly Top")
		(33 "B.Fab" user "Ref Des/Assembly Bottom")
	)
	(footprint ""
		(layer "F.Cu")
		(at 77.101954 -342.726264 -90)
		(property "Reference" "PC482_P1_7"
			(at 0 0 270)
			(layer "F.SilkS")
			(hide yes)
			(effects
				(font
					(size 1.27 1.27)
				)
			)
		)
		(property "Value" ""
			(at 0 0 270)
			(layer "F.Fab")
			(effects
				(font
					(size 1.27 1.27)
				)
			)
		)
		(duplicate_pad_numbers_are_jumpers no)
		(fp_line
			(start -0.7874 0.4064)
			(end -0.7874 -0.4064)
			(stroke
				(width 0.1524)
				(type default)
			)
			(layer "F.SilkS")
		)
		(fp_line
			(start 0.7874 0.4064)
			(end -0.7874 0.4064)
			(stroke
				(width 0.1524)
				(type default)
			)
			(layer "F.SilkS")
		)
		(fp_line
			(start -0.7874 -0.4064)
			(end 0.7874 -0.4064)
			(stroke
				(width 0.1524)
				(type default)
			)
			(layer "F.SilkS")
		)
		(fp_line
			(start 0.7874 -0.4064)
			(end 0.7874 0.4064)
			(stroke
				(width 0.1524)
				(type default)
			)
			(layer "F.SilkS")
		)
		(fp_line
			(start -0.67945 0.3048)
			(end -0.67945 -0.305054)
			(stroke
				(width 0.1)
				(type default)
			)
			(layer "F.Fab")
		)
		(fp_line
			(start -0.12065 0.3048)
			(end -0.67945 0.3048)
			(stroke
				(width 0.1)
				(type default)
			)
			(layer "F.Fab")
		)
		(fp_line
			(start 0.120396 0.3048)
			(end 0.120396 0.2794)
			(stroke
				(width 0.1)
				(type default)
			)
			(layer "F.Fab")
		)
		(fp_line
			(start 0.67945 0.3048)
			(end 0.120396 0.3048)
			(stroke
				(width 0.1)
				(type default)
			)
			(layer "F.Fab")
		)
		(fp_line
			(start -0.12065 0.2794)
			(end -0.12065 0.3048)
			(stroke
				(width 0.1)
				(type default)
			)
			(layer "F.Fab")
		)
		(fp_line
			(start 0.120396 0.2794)
			(end -0.12065 0.2794)
			(stroke
				(width 0.1)
				(type default)
			)
			(layer "F.Fab")
		)
		(fp_line
			(start -0.12065 -0.2794)
			(end 0.12065 -0.2794)
			(stroke
				(width 0.1)
				(type default)
			)
			(layer "F.Fab")
		)
		(fp_line
			(start 0.12065 -0.2794)
			(end 0.12065 -0.3048)
			(stroke
				(width 0.1)
				(type default)
			)
			(layer "F.Fab")
		)
		(fp_line
			(start 0.12065 -0.3048)
			(end 0.67945 -0.3048)
			(stroke
				(width 0.1)
				(type default)
			)
			(layer "F.Fab")
		)
		(fp_line
			(start 0.67945 -0.3048)
			(end 0.67945 0.3048)
			(stroke
				(width 0.1)
				(type default)
			)
			(layer "F.Fab")
		)
		(fp_line
			(start -0.67945 -0.305054)
			(end -0.12065 -0.305054)
			(stroke
				(width 0.1)
				(type default)
			)
			(layer "F.Fab")
		)
		(fp_line
			(start -0.12065 -0.305054)
			(end -0.12065 -0.2794)
			(stroke
				(width 0.1)
				(type default)
			)
			(layer "F.Fab")
		)
		(pad "1" smd circle
			(at -0.40005 0 270)
			(size 0 0)
			(layers "F.Cu" "F.Mask" "F.Paste")
			(net "PVCCIN_CPU1_PVCC")
		)
		(pad "2" smd circle
			(at 0.40005 0 270)
			(size 0 0)
			(layers "F.Cu" "F.Mask" "F.Paste")
			(net "GND")
		)
	)
	(footprint ""
		(layer "F.Cu")
		(at 304.1396 -419.10635 -90)
		(property "Reference" "C2264"
			(at 0 0 270)
			(layer "F.SilkS")
			(hide yes)
			(effects
				(font
					(size 1.27 1.27)
				)
			)
		)
		(property "Value" ""
			(at 0 0 270)
			(layer "F.Fab")
			(effects
				(font
					(size 1.27 1.27)
				)
			)
		)
		(duplicate_pad_numbers_are_jumpers no)
		(fp_line
			(start -0.7874 0.4064)
			(end -0.7874 -0.4064)
			(stroke
				(width 0.1524)
				(type default)
			)
			(layer "F.SilkS")
		)
		(fp_line
			(start 0.7874 0.4064)
			(end -0.7874 0.4064)
			(stroke
				(width 0.1524)
				(type default)
			)
			(layer "F.SilkS")
		)
		(fp_line
			(start -0.7874 -0.4064)
			(end 0.7874 -0.4064)
			(stroke
				(width 0.1524)
				(type default)
			)
			(layer "F.SilkS")
		)
		(fp_line
			(start 0.7874 -0.4064)
			(end 0.7874 0.4064)
			(stroke
				(width 0.1524)
				(type default)
			)
			(layer "F.SilkS")
		)
		(fp_line
			(start -0.67945 0.3048)
			(end -0.67945 -0.305054)
			(stroke
				(width 0.1)
				(type default)
			)
			(layer "F.Fab")
		)
		(fp_line
			(start -0.12065 0.3048)
			(end -0.67945 0.3048)
			(stroke
				(width 0.1)
				(type default)
			)
			(layer "F.Fab")
		)
		(fp_line
			(start 0.120396 0.3048)
			(end 0.120396 0.2794)
			(stroke
				(width 0.1)
				(type default)
			)
			(layer "F.Fab")
		)
		(fp_line
			(start 0.67945 0.3048)
			(end 0.120396 0.3048)
			(stroke
				(width 0.1)
				(type default)
			)
			(layer "F.Fab")
		)
		(fp_line
			(start -0.12065 0.2794)
			(end -0.12065 0.3048)
			(stroke
				(width 0.1)
				(type default)
			)
			(layer "F.Fab")
		)
		(fp_line
			(start 0.120396 0.2794)
			(end -0.12065 0.2794)
			(stroke
				(width 0.1)
				(type default)
			)
			(layer "F.Fab")
		)
		(fp_line
			(start -0.12065 -0.2794)
			(end 0.12065 -0.2794)
			(stroke
				(width 0.1)
				(type default)
			)
			(layer "F.Fab")
		)
		(fp_line
			(start 0.12065 -0.2794)
			(end 0.12065 -0.3048)
			(stroke
				(width 0.1)
				(type default)
			)
			(layer "F.Fab")
		)
		(fp_line
			(start 0.12065 -0.3048)
			(end 0.67945 -0.3048)
			(stroke
				(width 0.1)
				(type default)
			)
			(layer "F.Fab")
		)
		(fp_line
			(start 0.67945 -0.3048)
			(end 0.67945 0.3048)
			(stroke
				(width 0.1)
				(type default)
			)
			(layer "F.Fab")
		)
		(fp_line
			(start -0.67945 -0.305054)
			(end -0.12065 -0.305054)
			(stroke
				(width 0.1)
				(type default)
			)
			(layer "F.Fab")
		)
		(fp_line
			(start -0.12065 -0.305054)
			(end -0.12065 -0.2794)
			(stroke
				(width 0.1)
				(type default)
			)
			(layer "F.Fab")
		)
		(pad "1" smd circle
			(at -0.40005 0 270)
			(size 0 0)
			(layers "F.Cu" "F.Mask" "F.Paste")
			(net "GPU_3V3IO_RSVD0_FFU_ISO")
		)
		(pad "2" smd circle
			(at 0.40005 0 270)
			(size 0 0)
			(layers "F.Cu" "F.Mask" "F.Paste")
			(net "GND")
		)
	)
)
